(kicad_pcb
	(version 20260206)
	(generator "pcbnew")
	(generator_version "10.0")
	(general
		(thickness 1.6)
		(legacy_teardrops no)
	)
	(paper "A4")
	(title_block
		(title "baseboard — 13948-1b.1110WZS1818.brd")
		(comment 1 "Honey Badger (Wiwynn) / footprints 1404-1411 of 2523")
	)
	(layers
		(0 "F.Cu" signal "TOP")
		(4 "In1.Cu" signal "L2GND")
		(6 "In2.Cu" signal "L3")
		(8 "In3.Cu" signal "L4VCC")
		(10 "In4.Cu" signal "L5VCC")
		(12 "In5.Cu" signal "L6")
		(14 "In6.Cu" signal "L7GND")
		(2 "B.Cu" signal "BOTTOM")
		(9 "F.Adhes" user "F.Adhesive")
		(11 "B.Adhes" user "B.Adhesive")
		(13 "F.Paste" user "Package Geometry/Pastemask Top")
		(15 "B.Paste" user "Package Geometry/Pastemask Bottom")
		(5 "F.SilkS" user "Ref Des/Silkscreen Top")
		(7 "B.SilkS" user "Ref Des/Silkscreen Bottom")
		(1 "F.Mask" user "Board Geometry/Soldermask Top")
		(3 "B.Mask" user "Board Geometry/Soldermask Bottom")
		(17 "Dwgs.User" user "User.Drawings")
		(19 "Cmts.User" user "User.Comments")
		(21 "Eco1.User" user "User.Eco1")
		(23 "Eco2.User" user "User.Eco2")
		(25 "Edge.Cuts" user "Board Geometry/Outline")
		(27 "Margin" user)
		(31 "F.CrtYd" user "Package Geometry/Place Bound Top")
		(29 "B.CrtYd" user "Package Geometry/Place Bound Bottom")
		(35 "F.Fab" user "Ref Des/Assembly Top")
		(33 "B.Fab" user "Ref Des/Assembly Bottom")
	)
	(footprint ""
		(layer "F.Cu")
		(at 152.247092 -110.773464 -90)
		(property "Reference" "SR834"
			(at 0 0 270)
			(layer "F.SilkS")
			(hide yes)
			(effects
				(font
					(size 1.27 1.27)
				)
			)
		)
		(property "Value" "D51R3F-2-GP"
			(at -0.0254 -2.5146 270)
			(unlocked yes)
			(layer "F.Fab")
			(hide yes)
			(effects
				(font
					(size 1.016 1.016)
					(thickness 0.1524)
				)
			)
		)
		(property "Device Type" "R603H22"
			(at -0.0254 -4.0386 270)
			(unlocked yes)
			(layer "F.Fab")
			(hide yes)
			(effects
				(font
					(size 1.016 1.016)
					(thickness 0.1524)
				)
			)
		)
		(duplicate_pad_numbers_are_jumpers no)
		(fp_line
			(start -0.4826 0)
			(end -0.2032 0)
			(stroke
				(width 0.2032)
				(type default)
			)
			(layer "F.SilkS")
		)
		(fp_line
			(start 0.2032 0)
			(end 0.4826 0)
			(stroke
				(width 0.2032)
				(type default)
			)
			(layer "F.SilkS")
		)
		(fp_rect
			(start -0.5842 1.3335)
			(end 0.5842 -1.3335)
			(stroke
				(width 0)
				(type default)
			)
			(fill no)
			(layer "F.CrtYd")
		)
		(fp_rect
			(start -0.5842 1.3335)
			(end 0.5842 -1.3335)
			(stroke
				(width 0)
				(type default)
			)
			(fill no)
			(layer "F.Fab")
		)
		(pad "1" smd custom
			(at 0 -0.762 270)
			(size 0.2159 0.2159)
			(layers "F.Cu" "F.Mask" "F.Paste")
			(net "P0V9_E")
			(options
				(clearance outline)
				(anchor circle)
			)
			(primitives
				(gr_poly
					(pts
						(arc
							(start -0.3302 -0.4318)
							(mid -0.402042 -0.402042)
							(end -0.4318 -0.3302)
						)
						(arc
							(start -0.4318 0.3302)
							(mid -0.402042 0.402042)
							(end -0.3302 0.4318)
						)
						(arc
							(start 0.3302 0.4318)
							(mid 0.402042 0.402042)
							(end 0.4318 0.3302)
						)
						(arc
							(start 0.4318 -0.3302)
							(mid 0.402042 -0.402042)
							(end 0.3302 -0.4318)
						)
					)
					(width 0)
					(fill yes)
				)
			)
		)
		(pad "2" smd custom
			(at 0 0.762 270)
			(size 0.2159 0.2159)
			(layers "F.Cu" "F.Mask" "F.Paste")
			(net "GB_VDDA")
			(options
				(clearance outline)
				(anchor circle)
			)
			(primitives
				(gr_poly
					(pts
						(arc
							(start -0.3302 -0.4318)
							(mid -0.402042 -0.402042)
							(end -0.4318 -0.3302)
						)
						(arc
							(start -0.4318 0.3302)
							(mid -0.402042 0.402042)
							(end -0.3302 0.4318)
						)
						(arc
							(start 0.3302 0.4318)
							(mid 0.402042 0.402042)
							(end 0.4318 0.3302)
						)
						(arc
							(start 0.4318 -0.3302)
							(mid 0.402042 -0.402042)
							(end 0.3302 -0.4318)
						)
					)
					(width 0)
					(fill yes)
				)
			)
		)
	)
	(footprint ""
		(layer "F.Cu")
		(at 184.031128 -16.183864 180)
		(property "Reference" "R196"
			(at 0 0 180)
			(layer "F.SilkS")
			(hide yes)
			(effects
				(font
					(size 1.27 1.27)
				)
			)
		)
		(property "Value" "4K7R2F-GP"
			(at 0.064008 -3.993896 180)
			(unlocked yes)
			(layer "F.Fab")
			(hide yes)
			(effects
				(font
					(size 1.016 1.016)
					(thickness 0.1524)
				)
			)
		)
		(property "Device Type" "R402H16"
			(at 0.064008 -5.517896 180)
			(unlocked yes)
			(layer "F.Fab")
			(hide yes)
			(effects
				(font
					(size 1.016 1.016)
					(thickness 0.1524)
				)
			)
		)
		(duplicate_pad_numbers_are_jumpers no)
		(fp_line
			(start 0.508 -0.9398)
			(end -0.508 -0.9398)
			(stroke
				(width 0.1524)
				(type default)
			)
			(layer "F.SilkS")
		)
		(fp_line
			(start -0.508 -0.9398)
			(end -0.508 0.9398)
			(stroke
				(width 0.1524)
				(type default)
			)
			(layer "F.SilkS")
		)
		(fp_rect
			(start -0.508 0.9398)
			(end 0.508 -0.9398)
			(stroke
				(width 0)
				(type default)
			)
			(fill no)
			(layer "F.CrtYd")
		)
		(fp_rect
			(start -0.508 0.9398)
			(end 0.508 -0.9398)
			(stroke
				(width 0)
				(type default)
			)
			(fill no)
			(layer "F.Fab")
		)
		(pad "1" smd custom
			(at 0 -0.4445 180)
			(size 0.1397 0.1397)
			(layers "F.Cu" "F.Mask" "F.Paste")
			(net "TEMP_1_A1")
			(options
				(clearance outline)
				(anchor circle)
			)
			(primitives
				(gr_poly
					(pts
						(arc
							(start -0.1778 -0.2794)
							(mid -0.249642 -0.249642)
							(end -0.2794 -0.1778)
						)
						(arc
							(start -0.2794 0.1778)
							(mid -0.249642 0.249642)
							(end -0.1778 0.2794)
						)
						(arc
							(start 0.1778 0.2794)
							(mid 0.249642 0.249642)
							(end 0.2794 0.1778)
						)
						(arc
							(start 0.2794 -0.1778)
							(mid 0.249642 -0.249642)
							(end 0.1778 -0.2794)
						)
					)
					(width 0)
					(fill yes)
				)
			)
		)
		(pad "2" smd custom
			(at 0 0.4445 180)
			(size 0.1397 0.1397)
			(layers "F.Cu" "F.Mask" "F.Paste")
			(net "GND")
			(options
				(clearance outline)
				(anchor circle)
			)
			(primitives
				(gr_poly
					(pts
						(arc
							(start -0.1778 -0.2794)
							(mid -0.249642 -0.249642)
							(end -0.2794 -0.1778)
						)
						(arc
							(start -0.2794 0.1778)
							(mid -0.249642 0.249642)
							(end -0.1778 0.2794)
						)
						(arc
							(start 0.1778 0.2794)
							(mid 0.249642 0.249642)
							(end 0.2794 0.1778)
						)
						(arc
							(start 0.2794 -0.1778)
							(mid 0.249642 -0.249642)
							(end 0.1778 -0.2794)
						)
					)
					(width 0)
					(fill yes)
				)
			)
		)
	)
	(footprint ""
		(layer "F.Cu")
		(at 187.481718 -138.802872)
		(property "Reference" "SC1108"
			(at 0 0 0)
			(layer "F.SilkS")
			(hide yes)
			(effects
				(font
					(size 1.27 1.27)
				)
			)
		)
		(property "Value" "SCD1U16V2KX-3GP"
			(at 1.1811 -2.7051 0)
			(unlocked yes)
			(layer "F.Fab")
			(hide yes)
			(effects
				(font
					(size 1.016 1.016)
					(thickness 0.1524)
				)
			)
		)
		(property "Device Type" "C402H22"
			(at 1.1811 -4.2291 0)
			(unlocked yes)
			(layer "F.Fab")
			(hide yes)
			(effects
				(font
					(size 1.016 1.016)
					(thickness 0.1524)
				)
			)
		)
		(duplicate_pad_numbers_are_jumpers no)
		(fp_rect
			(start -0.4318 0.9525)
			(end 0.4318 -0.9525)
			(stroke
				(width 0)
				(type default)
			)
			(fill no)
			(layer "F.CrtYd")
		)
		(fp_rect
			(start -0.4318 0.9525)
			(end 0.4318 -0.9525)
			(stroke
				(width 0)
				(type default)
			)
			(fill no)
			(layer "F.Fab")
		)
		(pad "1" smd custom
			(at 0 -0.4445)
			(size 0.1524 0.1524)
			(layers "F.Cu" "F.Mask" "F.Paste")
			(net "P1V8_E")
			(options
				(clearance outline)
				(anchor circle)
			)
			(primitives
				(gr_poly
					(pts
						(arc
							(start 0.3048 -0.2032)
							(mid 0.275042 -0.275042)
							(end 0.2032 -0.3048)
						)
						(arc
							(start -0.2032 -0.3048)
							(mid -0.275042 -0.275042)
							(end -0.3048 -0.2032)
						)
						(arc
							(start -0.3048 0.2032)
							(mid -0.275042 0.275042)
							(end -0.2032 0.3048)
						)
						(arc
							(start 0.2032 0.3048)
							(mid 0.275042 0.275042)
							(end 0.3048 0.2032)
						)
					)
					(width 0)
					(fill yes)
				)
			)
		)
		(pad "2" smd custom
			(at 0 0.4445)
			(size 0.1524 0.1524)
			(layers "F.Cu" "F.Mask" "F.Paste")
			(net "GND")
			(options
				(clearance outline)
				(anchor circle)
			)
			(primitives
				(gr_poly
					(pts
						(arc
							(start 0.3048 -0.2032)
							(mid 0.275042 -0.275042)
							(end 0.2032 -0.3048)
						)
						(arc
							(start -0.2032 -0.3048)
							(mid -0.275042 -0.275042)
							(end -0.3048 -0.2032)
						)
						(arc
							(start -0.3048 0.2032)
							(mid -0.275042 0.275042)
							(end -0.2032 0.3048)
						)
						(arc
							(start 0.2032 0.3048)
							(mid 0.275042 0.275042)
							(end 0.3048 0.2032)
						)
					)
					(width 0)
					(fill yes)
				)
			)
		)
	)
	(footprint ""
		(layer "F.Cu")
		(at 242.6843 -114.4778 90)
		(property "Reference" "U185"
			(at 0 0 90)
			(layer "F.SilkS")
			(hide yes)
			(effects
				(font
					(size 1.27 1.27)
				)
			)
		)
		(property "Value" "TXS0102DCUR-1-GP"
			(at 0 -11.1252 90)
			(unlocked yes)
			(layer "F.Fab")
			(hide yes)
			(effects
				(font
					(size 1.016 1.016)
					(thickness 0.1524)
				)
			)
		)
		(property "Device Type" "SSOIC8-4H36"
			(at 0 -12.6492 90)
			(unlocked yes)
			(layer "F.Fab")
			(hide yes)
			(effects
				(font
					(size 1.016 1.016)
					(thickness 0.1524)
				)
			)
		)
		(duplicate_pad_numbers_are_jumpers no)
		(fp_line
			(start 1.2573 -2.1844)
			(end 1.2573 2.1844)
			(stroke
				(width 0.1524)
				(type default)
			)
			(layer "F.SilkS")
		)
		(fp_line
			(start -1.2573 -2.1844)
			(end 1.2573 -2.1844)
			(stroke
				(width 0.1524)
				(type default)
			)
			(layer "F.SilkS")
		)
		(fp_line
			(start -1.2192 -0.3556)
			(end -0.9017 -0.0381)
			(stroke
				(width 0.1524)
				(type default)
			)
			(layer "F.SilkS")
		)
		(fp_line
			(start -1.2573 -0.3556)
			(end -1.2192 -0.3556)
			(stroke
				(width 0.1524)
				(type default)
			)
			(layer "F.SilkS")
		)
		(fp_line
			(start -0.9017 -0.0381)
			(end -1.2065 0.2667)
			(stroke
				(width 0.1524)
				(type default)
			)
			(layer "F.SilkS")
		)
		(fp_line
			(start -1.2065 0.2667)
			(end -1.27 0.2667)
			(stroke
				(width 0.1524)
				(type default)
			)
			(layer "F.SilkS")
		)
		(fp_line
			(start -1.2954 0.4572)
			(end -1.2954 2.159)
			(stroke
				(width 0.4064)
				(type default)
			)
			(layer "F.SilkS")
		)
		(fp_line
			(start 1.2573 2.1844)
			(end -1.2573 2.1844)
			(stroke
				(width 0.1524)
				(type default)
			)
			(layer "F.SilkS")
		)
		(fp_line
			(start -1.2573 2.1844)
			(end -1.2573 -2.1844)
			(stroke
				(width 0.1524)
				(type default)
			)
			(layer "F.SilkS")
		)
		(fp_poly
			(pts
				(xy -1.5113 2.4384) (xy 1.5113 2.4384) (xy 1.5113 -2.4384) (xy -1.5113 -2.4384)
			)
			(stroke
				(width 0)
				(type default)
			)
			(fill no)
			(layer "F.CrtYd")
		)
		(fp_poly
			(pts
				(xy -1.5113 -2.4384) (xy 1.5113 -2.4384) (xy 1.5113 2.4384) (xy -1.5113 2.4384)
			)
			(stroke
				(width 0)
				(type default)
			)
			(fill no)
			(layer "F.Fab")
		)
		(pad "1" smd rect
			(at -0.75057 1.1684 90)
			(size 0.3048 1.524)
			(layers "F.Cu" "F.Mask" "F.Paste")
			(net "EXP_SMART_RX_R")
		)
		(pad "2" smd rect
			(at -0.25019 1.1684 90)
			(size 0.3048 1.524)
			(layers "F.Cu" "F.Mask" "F.Paste")
			(net "GND")
		)
		(pad "3" smd rect
			(at 0.25019 1.1684 90)
			(size 0.3048 1.524)
			(layers "F.Cu" "F.Mask" "F.Paste")
			(net "P1V8_E")
		)
		(pad "4" smd rect
			(at 0.75057 1.1684 90)
			(size 0.3048 1.524)
			(layers "F.Cu" "F.Mask" "F.Paste")
			(net "SAS_SMART_R_RX")
		)
		(pad "5" smd rect
			(at 0.75057 -1.1684 90)
			(size 0.3048 1.524)
			(layers "F.Cu" "F.Mask" "F.Paste")
			(net "SAS_SMART_R_TX")
		)
		(pad "6" smd rect
			(at 0.25019 -1.1684 90)
			(size 0.3048 1.524)
			(layers "F.Cu" "F.Mask" "F.Paste")
			(net "SMART_UART_EN")
		)
		(pad "7" smd rect
			(at -0.25019 -1.1684 90)
			(size 0.3048 1.524)
			(layers "F.Cu" "F.Mask" "F.Paste")
			(net "P3V3_STBY")
		)
		(pad "8" smd rect
			(at -0.75057 -1.1684 90)
			(size 0.3048 1.524)
			(layers "F.Cu" "F.Mask" "F.Paste")
			(net "EXP_SMART_TX_R")
		)
	)
	(footprint ""
		(layer "F.Cu")
		(at 48.387 -216.408 -90)
		(property "Reference" "C7317"
			(at 0 0 270)
			(layer "F.SilkS")
			(hide yes)
			(effects
				(font
					(size 1.27 1.27)
				)
			)
		)
		(property "Value" "SCD1U25V3JX-GP"
			(at 0 -2.8194 270)
			(unlocked yes)
			(layer "F.Fab")
			(hide yes)
			(effects
				(font
					(size 1.016 1.016)
					(thickness 0.1524)
				)
			)
		)
		(property "Device Type" "C603H36"
			(at 0 -4.3434 270)
			(unlocked yes)
			(layer "F.Fab")
			(hide yes)
			(effects
				(font
					(size 1.016 1.016)
					(thickness 0.1524)
				)
			)
		)
		(duplicate_pad_numbers_are_jumpers no)
		(fp_line
			(start 0.508 0)
			(end -0.508 0)
			(stroke
				(width 0.2032)
				(type default)
			)
			(layer "F.SilkS")
		)
		(fp_rect
			(start -0.5842 1.3335)
			(end 0.5842 -1.3335)
			(stroke
				(width 0)
				(type default)
			)
			(fill no)
			(layer "F.CrtYd")
		)
		(fp_rect
			(start -0.5842 1.3335)
			(end 0.5842 -1.3335)
			(stroke
				(width 0)
				(type default)
			)
			(fill no)
			(layer "F.Fab")
		)
		(pad "1" smd custom
			(at 0 -0.762 270)
			(size 0.2159 0.2159)
			(layers "F.Cu" "F.Mask" "F.Paste")
			(net "MB0_ISTART_R")
			(options
				(clearance outline)
				(anchor circle)
			)
			(primitives
				(gr_poly
					(pts
						(arc
							(start -0.3302 -0.4318)
							(mid -0.402042 -0.402042)
							(end -0.4318 -0.3302)
						)
						(arc
							(start -0.4318 0.3302)
							(mid -0.402042 0.402042)
							(end -0.3302 0.4318)
						)
						(arc
							(start 0.3302 0.4318)
							(mid 0.402042 0.402042)
							(end 0.4318 0.3302)
						)
						(arc
							(start 0.4318 -0.3302)
							(mid 0.402042 -0.402042)
							(end 0.3302 -0.4318)
						)
					)
					(width 0)
					(fill yes)
				)
			)
		)
		(pad "2" smd custom
			(at 0 0.762 270)
			(size 0.2159 0.2159)
			(layers "F.Cu" "F.Mask" "F.Paste")
			(net "AGND_CURRENT_MON")
			(options
				(clearance outline)
				(anchor circle)
			)
			(primitives
				(gr_poly
					(pts
						(arc
							(start -0.3302 -0.4318)
							(mid -0.402042 -0.402042)
							(end -0.4318 -0.3302)
						)
						(arc
							(start -0.4318 0.3302)
							(mid -0.402042 0.402042)
							(end -0.3302 0.4318)
						)
						(arc
							(start 0.3302 0.4318)
							(mid 0.402042 0.402042)
							(end 0.4318 0.3302)
						)
						(arc
							(start 0.4318 -0.3302)
							(mid 0.402042 -0.402042)
							(end 0.3302 -0.4318)
						)
					)
					(width 0)
					(fill yes)
				)
			)
		)
	)
	(footprint ""
		(layer "F.Cu")
		(at 261.239 -65.532)
		(property "Reference" "C257"
			(at 0 0 0)
			(layer "F.SilkS")
			(hide yes)
			(effects
				(font
					(size 1.27 1.27)
				)
			)
		)
		(property "Value" "SC22U25V5MX-GP"
			(at -0.0762 -6.1214 0)
			(unlocked yes)
			(layer "F.Fab")
			(hide yes)
			(effects
				(font
					(size 1.016 1.016)
					(thickness 0.1524)
				)
			)
		)
		(property "Device Type" "C805H58"
			(at -0.0762 -8.1534 0)
			(unlocked yes)
			(layer "F.Fab")
			(hide yes)
			(effects
				(font
					(size 1.016 1.016)
					(thickness 0.1524)
				)
			)
		)
		(duplicate_pad_numbers_are_jumpers no)
		(fp_line
			(start 0.635 0)
			(end -0.635 0)
			(stroke
				(width 0.508)
				(type default)
			)
			(layer "F.SilkS")
		)
		(fp_rect
			(start -0.9652 1.778)
			(end 0.9652 -1.778)
			(stroke
				(width 0)
				(type default)
			)
			(fill no)
			(layer "F.CrtYd")
		)
		(fp_poly
			(pts
				(xy -0.9652 -1.778) (xy 0.9652 -1.778) (xy 0.9652 1.778) (xy -0.9652 1.778)
			)
			(stroke
				(width 0)
				(type default)
			)
			(fill no)
			(layer "F.Fab")
		)
		(pad "1" smd rect
			(at 0 -0.9652)
			(size 1.397 1.143)
			(layers "F.Cu" "F.Mask" "F.Paste")
			(net "P12V_MSB")
		)
		(pad "2" smd rect
			(at 0 0.9652)
			(size 1.397 1.143)
			(layers "F.Cu" "F.Mask" "F.Paste")
			(net "GND")
		)
	)
	(footprint ""
		(layer "F.Cu")
		(at 314.198 -190.5)
		(property "Reference" "TP180"
			(at 0 0 0)
			(layer "F.SilkS")
			(hide yes)
			(effects
				(font
					(size 1.27 1.27)
				)
			)
		)
		(property "Value" "TPAD28"
			(at -0.0127 -1.6637 0)
			(unlocked yes)
			(layer "F.Fab")
			(hide yes)
			(effects
				(font
					(size 1.016 1.016)
					(thickness 0.1524)
				)
			)
		)
		(property "Device Type" "TPAD28"
			(at -0.0127 -3.1877 0)
			(unlocked yes)
			(layer "F.Fab")
			(hide yes)
			(effects
				(font
					(size 1.016 1.016)
					(thickness 0.1524)
				)
			)
		)
		(duplicate_pad_numbers_are_jumpers no)
		(fp_poly
			(pts
				(arc
					(start 0.3556 0)
					(mid -0.3556 0)
					(end 0.3556 0)
				)
			)
			(stroke
				(width 0)
				(type default)
			)
			(fill no)
			(layer "F.CrtYd")
		)
		(fp_poly
			(pts
				(arc
					(start 0.6096 0)
					(mid -0.6096 0)
					(end 0.6096 0)
				)
			)
			(stroke
				(width 0)
				(type default)
			)
			(fill no)
			(layer "F.Fab")
		)
		(pad "1" smd circle
			(at 0 0)
			(size 0.7112 0.7112)
			(layers "F.Cu" "F.Mask" "F.Paste")
			(net "JTAG_BMC_TDO")
		)
	)
	(footprint ""
		(layer "F.Cu")
		(at 166.360348 -122.545856 180)
		(property "Reference" "PR162"
			(at 0 0 180)
			(layer "F.SilkS")
			(hide yes)
			(effects
				(font
					(size 1.27 1.27)
				)
			)
		)
		(property "Value" "187KR2F-GP"
			(at 0.064008 -3.993896 180)
			(unlocked yes)
			(layer "F.Fab")
			(hide yes)
			(effects
				(font
					(size 1.016 1.016)
					(thickness 0.1524)
				)
			)
		)
		(property "Device Type" "R402H16"
			(at 0.064008 -5.517896 180)
			(unlocked yes)
			(layer "F.Fab")
			(hide yes)
			(effects
				(font
					(size 1.016 1.016)
					(thickness 0.1524)
				)
			)
		)
		(duplicate_pad_numbers_are_jumpers no)
		(fp_line
			(start 0.508 -0.9398)
			(end -0.508 -0.9398)
			(stroke
				(width 0.1524)
				(type default)
			)
			(layer "F.SilkS")
		)
		(fp_line
			(start -0.508 -0.9398)
			(end -0.508 0.9398)
			(stroke
				(width 0.1524)
				(type default)
			)
			(layer "F.SilkS")
		)
		(fp_rect
			(start -0.508 0.9398)
			(end 0.508 -0.9398)
			(stroke
				(width 0)
				(type default)
			)
			(fill no)
			(layer "F.CrtYd")
		)
		(fp_rect
			(start -0.508 0.9398)
			(end 0.508 -0.9398)
			(stroke
				(width 0)
				(type default)
			)
			(fill no)
			(layer "F.Fab")
		)
		(pad "1" smd custom
			(at 0 -0.4445 180)
			(size 0.1397 0.1397)
			(layers "F.Cu" "F.Mask" "F.Paste")
			(net "P0V9_E_RF")
			(options
				(clearance outline)
				(anchor circle)
			)
			(primitives
				(gr_poly
					(pts
						(arc
							(start -0.1778 -0.2794)
							(mid -0.249642 -0.249642)
							(end -0.2794 -0.1778)
						)
						(arc
							(start -0.2794 0.1778)
							(mid -0.249642 0.249642)
							(end -0.1778 0.2794)
						)
						(arc
							(start 0.1778 0.2794)
							(mid 0.249642 0.249642)
							(end 0.2794 0.1778)
						)
						(arc
							(start 0.2794 -0.1778)
							(mid 0.249642 -0.249642)
							(end 0.1778 -0.2794)
						)
					)
					(width 0)
					(fill yes)
				)
			)
		)
		(pad "2" smd custom
			(at 0 0.4445 180)
			(size 0.1397 0.1397)
			(layers "F.Cu" "F.Mask" "F.Paste")
			(net "AGND_P0V9_E")
			(options
				(clearance outline)
				(anchor circle)
			)
			(primitives
				(gr_poly
					(pts
						(arc
							(start -0.1778 -0.2794)
							(mid -0.249642 -0.249642)
							(end -0.2794 -0.1778)
						)
						(arc
							(start -0.2794 0.1778)
							(mid -0.249642 0.249642)
							(end -0.1778 0.2794)
						)
						(arc
							(start 0.1778 0.2794)
							(mid 0.249642 0.249642)
							(end 0.2794 0.1778)
						)
						(arc
							(start 0.2794 -0.1778)
							(mid 0.249642 -0.249642)
							(end 0.1778 -0.2794)
						)
					)
					(width 0)
					(fill yes)
				)
			)
		)
	)
)
